# S9S_MB_2U (Grand Teton) — schematic netlist excerpt (pin names and nets, part order shuffled) for the footprints in the layout excerpt that follows; sources: Cadence DE-HDL packaged netlist, KiCad conversion of 03242023_DA0F0TMBIJ0_F0T_Motherboard_J_brd_V01_OCP.brd

R815  Q_RES  0 5% CHIP  pkg 0402LF  page 130 : A = RST_PLD_CPU1_DRAM_GH_N ; B = RST_M_GH_CPU1_FPGA_N
PC613_P0_2  Q_CAP  1UF 16V 10% X6S  pkg C0402  page 271 : A = PVCCFA_EHV_FIVRA_CPU0 ; B = GND

(kicad_pcb
	(version 20260206)
	(generator "pcbnew")
	(generator_version "10.0")
	(general
		(thickness 1.6)
		(legacy_teardrops no)
	)
	(paper "A4")
	(title_block
		(title "03242023_DA0F0TMBIJ0_F0T_Motherboard_J_brd_V01_OCP.brd")
		(comment 1 "Grand Teton / footprints 5959-5960 of 6105")
	)
	(layers
		(0 "F.Cu" signal "TOP")
		(4 "In1.Cu" signal "GND")
		(6 "In2.Cu" signal "IN1")
		(8 "In3.Cu" signal "GND1")
		(10 "In4.Cu" signal "IN2")
		(12 "In5.Cu" signal "GND2")
		(14 "In6.Cu" signal "IN3")
		(16 "In7.Cu" signal "GND3")
		(18 "In8.Cu" signal "VCC")
		(20 "In9.Cu" signal "VCC1")
		(22 "In10.Cu" signal "GND4")
		(24 "In11.Cu" signal "IN4")
		(26 "In12.Cu" signal "GND5")
		(28 "In13.Cu" signal "IN5")
		(30 "In14.Cu" signal "GND6")
		(32 "In15.Cu" signal "IN6")
		(34 "In16.Cu" signal "GND7")
		(2 "B.Cu" signal "BOTTOM")
		(9 "F.Adhes" user "F.Adhesive")
		(11 "B.Adhes" user "B.Adhesive")
		(13 "F.Paste" user "Package Geometry/Pastemask Top")
		(15 "B.Paste" user "Package Geometry/Pastemask Bottom")
		(5 "F.SilkS" user "Ref Des/Silkscreen Top")
		(7 "B.SilkS" user "Ref Des/Silkscreen Bottom")
		(1 "F.Mask" user "Board Geometry/Soldermask Top")
		(3 "B.Mask" user "Board Geometry/Soldermask Bottom")
		(17 "Dwgs.User" user "User.Drawings")
		(19 "Cmts.User" user "User.Comments")
		(21 "Eco1.User" user "User.Eco1")
		(23 "Eco2.User" user "User.Eco2")
		(25 "Edge.Cuts" user "Board Geometry/Outline")
		(27 "Margin" user)
		(31 "F.CrtYd" user "Package Geometry/Place Bound Top")
		(29 "B.CrtYd" user "Package Geometry/Place Bound Bottom")
		(35 "F.Fab" user "Ref Des/Assembly Top")
		(33 "B.Fab" user "Ref Des/Assembly Bottom")
	)
	(footprint ""
		(layer "B.Cu")
		(at 301.724314 -353.955096 -90)
		(property "Reference" "PC613_P0_2"
			(at 0 0 90)
			(layer "B.SilkS")
			(hide yes)
			(effects
				(font
					(size 1.27 1.27)
				)
				(justify mirror)
			)
		)
		(property "Value" ""
			(at 0 0 90)
			(layer "B.Fab")
			(effects
				(font
					(size 1.27 1.27)
				)
				(justify mirror)
			)
		)
		(duplicate_pad_numbers_are_jumpers no)
		(fp_line
			(start -0.7874 0.4064)
			(end 0.7874 0.4064)
			(stroke
				(width 0.1524)
				(type default)
			)
			(layer "B.SilkS")
		)
		(fp_line
			(start 0.7874 0.4064)
			(end 0.7874 -0.4064)
			(stroke
				(width 0.1524)
				(type default)
			)
			(layer "B.SilkS")
		)
		(fp_line
			(start -0.7874 -0.4064)
			(end -0.7874 0.4064)
			(stroke
				(width 0.1524)
				(type default)
			)
			(layer "B.SilkS")
		)
		(fp_line
			(start 0.7874 -0.4064)
			(end -0.7874 -0.4064)
			(stroke
				(width 0.1524)
				(type default)
			)
			(layer "B.SilkS")
		)
		(fp_line
			(start -0.67945 0.3048)
			(end -0.120396 0.3048)
			(stroke
				(width 0.1)
				(type default)
			)
			(layer "B.Fab")
		)
		(fp_line
			(start -0.120396 0.3048)
			(end -0.120396 0.2794)
			(stroke
				(width 0.1)
				(type default)
			)
			(layer "B.Fab")
		)
		(fp_line
			(start 0.12065 0.3048)
			(end 0.67945 0.3048)
			(stroke
				(width 0.1)
				(type default)
			)
			(layer "B.Fab")
		)
		(fp_line
			(start 0.67945 0.3048)
			(end 0.67945 -0.305054)
			(stroke
				(width 0.1)
				(type default)
			)
			(layer "B.Fab")
		)
		(fp_line
			(start -0.120396 0.2794)
			(end 0.12065 0.2794)
			(stroke
				(width 0.1)
				(type default)
			)
			(layer "B.Fab")
		)
		(fp_line
			(start 0.12065 0.2794)
			(end 0.12065 0.3048)
			(stroke
				(width 0.1)
				(type default)
			)
			(layer "B.Fab")
		)
		(fp_line
			(start -0.12065 -0.2794)
			(end -0.12065 -0.3048)
			(stroke
				(width 0.1)
				(type default)
			)
			(layer "B.Fab")
		)
		(fp_line
			(start 0.12065 -0.2794)
			(end -0.12065 -0.2794)
			(stroke
				(width 0.1)
				(type default)
			)
			(layer "B.Fab")
		)
		(fp_line
			(start -0.67945 -0.3048)
			(end -0.67945 0.3048)
			(stroke
				(width 0.1)
				(type default)
			)
			(layer "B.Fab")
		)
		(fp_line
			(start -0.12065 -0.3048)
			(end -0.67945 -0.3048)
			(stroke
				(width 0.1)
				(type default)
			)
			(layer "B.Fab")
		)
		(fp_line
			(start 0.12065 -0.305054)
			(end 0.12065 -0.2794)
			(stroke
				(width 0.1)
				(type default)
			)
			(layer "B.Fab")
		)
		(fp_line
			(start 0.67945 -0.305054)
			(end 0.12065 -0.305054)
			(stroke
				(width 0.1)
				(type default)
			)
			(layer "B.Fab")
		)
		(pad "1" smd circle
			(at 0.40005 0 90)
			(size 0 0)
			(layers "B.Cu" "B.Mask" "B.Paste")
			(net "PVCCFA_EHV_FIVRA_CPU0")
		)
		(pad "2" smd circle
			(at -0.40005 0 90)
			(size 0 0)
			(layers "B.Cu" "B.Mask" "B.Paste")
			(net "GND")
		)
	)
	(footprint ""
		(layer "B.Cu")
		(at 190.248286 -193.615056 -90)
		(property "Reference" "R815"
			(at 0 0 90)
			(layer "B.SilkS")
			(hide yes)
			(effects
				(font
					(size 1.27 1.27)
				)
				(justify mirror)
			)
		)
		(property "Value" ""
			(at 0 0 90)
			(layer "B.Fab")
			(effects
				(font
					(size 1.27 1.27)
				)
				(justify mirror)
			)
		)
		(duplicate_pad_numbers_are_jumpers no)
		(fp_line
			(start -0.7874 0.4064)
			(end 0.7874 0.4064)
			(stroke
				(width 0.1524)
				(type default)
			)
			(layer "B.SilkS")
		)
		(fp_line
			(start 0.7874 0.4064)
			(end 0.7874 -0.4064)
			(stroke
				(width 0.1524)
				(type default)
			)
			(layer "B.SilkS")
		)
		(fp_line
			(start -0.7874 -0.4064)
			(end -0.7874 0.4064)
			(stroke
				(width 0.1524)
				(type default)
			)
			(layer "B.SilkS")
		)
		(fp_line
			(start 0.7874 -0.4064)
			(end -0.7874 -0.4064)
			(stroke
				(width 0.1524)
				(type default)
			)
			(layer "B.SilkS")
		)
		(fp_line
			(start -0.67945 0.3048)
			(end -0.120396 0.3048)
			(stroke
				(width 0.1)
				(type default)
			)
			(layer "B.Fab")
		)
		(fp_line
			(start -0.120396 0.3048)
			(end -0.120396 0.2794)
			(stroke
				(width 0.1)
				(type default)
			)
			(layer "B.Fab")
		)
		(fp_line
			(start 0.12065 0.3048)
			(end 0.67945 0.3048)
			(stroke
				(width 0.1)
				(type default)
			)
			(layer "B.Fab")
		)
		(fp_line
			(start 0.67945 0.3048)
			(end 0.67945 -0.305054)
			(stroke
				(width 0.1)
				(type default)
			)
			(layer "B.Fab")
		)
		(fp_line
			(start -0.120396 0.2794)
			(end 0.12065 0.2794)
			(stroke
				(width 0.1)
				(type default)
			)
			(layer "B.Fab")
		)
		(fp_line
			(start 0.12065 0.2794)
			(end 0.12065 0.3048)
			(stroke
				(width 0.1)
				(type default)
			)
			(layer "B.Fab")
		)
		(fp_line
			(start -0.12065 -0.2794)
			(end -0.12065 -0.3048)
			(stroke
				(width 0.1)
				(type default)
			)
			(layer "B.Fab")
		)
		(fp_line
			(start 0.12065 -0.2794)
			(end -0.12065 -0.2794)
			(stroke
				(width 0.1)
				(type default)
			)
			(layer "B.Fab")
		)
		(fp_line
			(start -0.67945 -0.3048)
			(end -0.67945 0.3048)
			(stroke
				(width 0.1)
				(type default)
			)
			(layer "B.Fab")
		)
		(fp_line
			(start -0.12065 -0.3048)
			(end -0.67945 -0.3048)
			(stroke
				(width 0.1)
				(type default)
			)
			(layer "B.Fab")
		)
		(fp_line
			(start 0.12065 -0.305054)
			(end 0.12065 -0.2794)
			(stroke
				(width 0.1)
				(type default)
			)
			(layer "B.Fab")
		)
		(fp_line
			(start 0.67945 -0.305054)
			(end 0.12065 -0.305054)
			(stroke
				(width 0.1)
				(type default)
			)
			(layer "B.Fab")
		)
		(pad "1" smd circle
			(at 0.40005 0 90)
			(size 0 0)
			(layers "B.Cu" "B.Mask" "B.Paste")
			(net "RST_PLD_CPU1_DRAM_GH_N")
		)
		(pad "2" smd circle
			(at -0.40005 0 90)
			(size 0 0)
			(layers "B.Cu" "B.Mask" "B.Paste")
			(net "RST_M_GH_CPU1_FPGA_N")
		)
	)
)
